(kicad_pcb
	(version 20260206)
	(generator "pcbnew")
	(generator_version "10.0")
	(general
		(thickness 1.6)
		(legacy_teardrops no)
	)
	(paper "A4")
	(title_block
		(title "03242023_DA0F0TMBIJ0_F0T_Motherboard_J_brd_V01_OCP.brd")
		(comment 1 "Grand Teton / footprint 3819 of 6105 (J18), pads 225-291 of 291")
	)
	(layers
		(0 "F.Cu" signal "TOP")
		(4 "In1.Cu" signal "GND")
		(6 "In2.Cu" signal "IN1")
		(8 "In3.Cu" signal "GND1")
		(10 "In4.Cu" signal "IN2")
		(12 "In5.Cu" signal "GND2")
		(14 "In6.Cu" signal "IN3")
		(16 "In7.Cu" signal "GND3")
		(18 "In8.Cu" signal "VCC")
		(20 "In9.Cu" signal "VCC1")
		(22 "In10.Cu" signal "GND4")
		(24 "In11.Cu" signal "IN4")
		(26 "In12.Cu" signal "GND5")
		(28 "In13.Cu" signal "IN5")
		(30 "In14.Cu" signal "GND6")
		(32 "In15.Cu" signal "IN6")
		(34 "In16.Cu" signal "GND7")
		(2 "B.Cu" signal "BOTTOM")
		(9 "F.Adhes" user "F.Adhesive")
		(11 "B.Adhes" user "B.Adhesive")
		(13 "F.Paste" user "Package Geometry/Pastemask Top")
		(15 "B.Paste" user "Package Geometry/Pastemask Bottom")
		(5 "F.SilkS" user "Ref Des/Silkscreen Top")
		(7 "B.SilkS" user "Ref Des/Silkscreen Bottom")
		(1 "F.Mask" user "Board Geometry/Soldermask Top")
		(3 "B.Mask" user "Board Geometry/Soldermask Bottom")
		(17 "Dwgs.User" user "User.Drawings")
		(19 "Cmts.User" user "User.Comments")
		(21 "Eco1.User" user "User.Eco1")
		(23 "Eco2.User" user "User.Eco2")
		(25 "Edge.Cuts" user "Board Geometry/Outline")
		(27 "Margin" user)
		(31 "F.CrtYd" user "Package Geometry/Place Bound Top")
		(29 "B.CrtYd" user "Package Geometry/Place Bound Bottom")
		(35 "F.Fab" user "Ref Des/Assembly Top")
		(33 "B.Fab" user "Ref Des/Assembly Bottom")
	)
	(footprint ""
		(layer "F.Cu")
		(at 62.99708 -258.091686)
		(property "Reference" "J18"
			(at -1.547622 -81.836514 0)
			(unlocked yes)
			(layer "F.SilkS")
			(effects
				(font
					(size 0.7874 0.5842)
					(thickness 0.1524)
				)
				(justify left)
			)
		)
		(property "Value" ""
			(at 0 0 0)
			(layer "F.Fab")
			(effects
				(font
					(size 1.27 1.27)
				)
			)
		)
		(duplicate_pad_numbers_are_jumpers no)
		(pad "225" smd rect
			(at 2.050034 9.774936 270)
			(size 0.519938 1.4986)
			(layers "F.Cu" "F.Mask" "F.Paste")
			(net "M_A_CPU1_SB_CA<5>")
		)
		(pad "226" smd rect
			(at 2.050034 10.625074 270)
			(size 0.519938 1.4986)
			(layers "F.Cu" "F.Mask" "F.Paste")
			(net "GND")
		)
		(pad "227" smd rect
			(at 2.050034 11.474958 270)
			(size 0.519938 1.4986)
			(layers "F.Cu" "F.Mask" "F.Paste")
			(net "M_A_CPU1_SB_PAR")
		)
		(pad "228" smd rect
			(at 2.050034 12.325096 270)
			(size 0.519938 1.4986)
			(layers "F.Cu" "F.Mask" "F.Paste")
			(net "GND")
		)
		(pad "229" smd rect
			(at 2.050034 13.17498 270)
			(size 0.519938 1.4986)
			(layers "F.Cu" "F.Mask" "F.Paste")
			(net "M_A_CPU1_SB_CS_N<3>")
		)
		(pad "230" smd rect
			(at 2.050034 14.025118 270)
			(size 0.519938 1.4986)
			(layers "F.Cu" "F.Mask" "F.Paste")
			(net "GND")
		)
		(pad "231" smd rect
			(at 2.050034 14.875002 270)
			(size 0.519938 1.4986)
			(layers "F.Cu" "F.Mask" "F.Paste")
			(net "TP_CHA_CPU1_DIMM2_FRU_5")
		)
		(pad "232" smd rect
			(at 2.050034 15.724886 270)
			(size 0.519938 1.4986)
			(layers "F.Cu" "F.Mask" "F.Paste")
			(net "TP_CHA_CPU1_DIMM2_FRU_6")
		)
		(pad "233" smd rect
			(at 2.050034 16.575024 270)
			(size 0.519938 1.4986)
			(layers "F.Cu" "F.Mask" "F.Paste")
			(net "GND")
		)
		(pad "234" smd rect
			(at 2.050034 17.424908 270)
			(size 0.519938 1.4986)
			(layers "F.Cu" "F.Mask" "F.Paste")
			(net "M_A_CPU1_SB_CB<6>")
		)
		(pad "235" smd rect
			(at 2.050034 18.275046 270)
			(size 0.519938 1.4986)
			(layers "F.Cu" "F.Mask" "F.Paste")
			(net "GND")
		)
		(pad "236" smd rect
			(at 2.050034 19.12493 270)
			(size 0.519938 1.4986)
			(layers "F.Cu" "F.Mask" "F.Paste")
			(net "M_A_CPU1_SB_CB<7>")
		)
		(pad "237" smd rect
			(at 2.050034 19.975068 270)
			(size 0.519938 1.4986)
			(layers "F.Cu" "F.Mask" "F.Paste")
			(net "GND")
		)
		(pad "238" smd rect
			(at 2.050034 20.824952 270)
			(size 0.519938 1.4986)
			(layers "F.Cu" "F.Mask" "F.Paste")
			(net "M_A_CPU1_SB_DQS_DN<4>")
		)
		(pad "239" smd rect
			(at 2.050034 21.67509 270)
			(size 0.519938 1.4986)
			(layers "F.Cu" "F.Mask" "F.Paste")
			(net "M_A_CPU1_SB_DQS_DP<4>")
		)
		(pad "240" smd rect
			(at 2.050034 22.524974 270)
			(size 0.519938 1.4986)
			(layers "F.Cu" "F.Mask" "F.Paste")
			(net "GND")
		)
		(pad "241" smd rect
			(at 2.050034 23.375112 270)
			(size 0.519938 1.4986)
			(layers "F.Cu" "F.Mask" "F.Paste")
			(net "M_A_CPU1_SB_CB<2>")
		)
		(pad "242" smd rect
			(at 2.050034 24.224996 270)
			(size 0.519938 1.4986)
			(layers "F.Cu" "F.Mask" "F.Paste")
			(net "GND")
		)
		(pad "243" smd rect
			(at 2.050034 25.07488 270)
			(size 0.519938 1.4986)
			(layers "F.Cu" "F.Mask" "F.Paste")
			(net "M_A_CPU1_SB_CB<3>")
		)
		(pad "244" smd rect
			(at 2.050034 25.925018 270)
			(size 0.519938 1.4986)
			(layers "F.Cu" "F.Mask" "F.Paste")
			(net "GND")
		)
		(pad "245" smd rect
			(at 2.050034 26.774902 270)
			(size 0.519938 1.4986)
			(layers "F.Cu" "F.Mask" "F.Paste")
			(net "M_A_CPU1_SB_DQ<2>")
		)
		(pad "246" smd rect
			(at 2.050034 27.62504 270)
			(size 0.519938 1.4986)
			(layers "F.Cu" "F.Mask" "F.Paste")
			(net "GND")
		)
		(pad "247" smd rect
			(at 2.050034 28.474924 270)
			(size 0.519938 1.4986)
			(layers "F.Cu" "F.Mask" "F.Paste")
			(net "M_A_CPU1_SB_DQ<3>")
		)
		(pad "248" smd rect
			(at 2.050034 29.325062 270)
			(size 0.519938 1.4986)
			(layers "F.Cu" "F.Mask" "F.Paste")
			(net "GND")
		)
		(pad "249" smd rect
			(at 2.050034 30.174946 270)
			(size 0.519938 1.4986)
			(layers "F.Cu" "F.Mask" "F.Paste")
			(net "M_A_CPU1_SB_DQS_DN<5>")
		)
		(pad "250" smd rect
			(at 2.050034 31.025084 270)
			(size 0.519938 1.4986)
			(layers "F.Cu" "F.Mask" "F.Paste")
			(net "M_A_CPU1_SB_DQS_DP<5>")
		)
		(pad "251" smd rect
			(at 2.050034 31.874968 270)
			(size 0.519938 1.4986)
			(layers "F.Cu" "F.Mask" "F.Paste")
			(net "GND")
		)
		(pad "252" smd rect
			(at 2.050034 32.725106 270)
			(size 0.519938 1.4986)
			(layers "F.Cu" "F.Mask" "F.Paste")
			(net "M_A_CPU1_SB_DQ<6>")
		)
		(pad "253" smd rect
			(at 2.050034 33.57499 270)
			(size 0.519938 1.4986)
			(layers "F.Cu" "F.Mask" "F.Paste")
			(net "GND")
		)
		(pad "254" smd rect
			(at 2.050034 34.425128 270)
			(size 0.519938 1.4986)
			(layers "F.Cu" "F.Mask" "F.Paste")
			(net "M_A_CPU1_SB_DQ<7>")
		)
		(pad "255" smd rect
			(at 2.050034 35.275012 270)
			(size 0.519938 1.4986)
			(layers "F.Cu" "F.Mask" "F.Paste")
			(net "GND")
		)
		(pad "256" smd rect
			(at 2.050034 36.124896 270)
			(size 0.519938 1.4986)
			(layers "F.Cu" "F.Mask" "F.Paste")
			(net "M_A_CPU1_SB_DQ<10>")
		)
		(pad "257" smd rect
			(at 2.050034 36.975034 270)
			(size 0.519938 1.4986)
			(layers "F.Cu" "F.Mask" "F.Paste")
			(net "GND")
		)
		(pad "258" smd rect
			(at 2.050034 37.824918 270)
			(size 0.519938 1.4986)
			(layers "F.Cu" "F.Mask" "F.Paste")
			(net "M_A_CPU1_SB_DQ<11>")
		)
		(pad "259" smd rect
			(at 2.050034 38.675056 270)
			(size 0.519938 1.4986)
			(layers "F.Cu" "F.Mask" "F.Paste")
			(net "GND")
		)
		(pad "260" smd rect
			(at 2.050034 39.52494 270)
			(size 0.519938 1.4986)
			(layers "F.Cu" "F.Mask" "F.Paste")
			(net "M_A_CPU1_SB_DQS_DN<6>")
		)
		(pad "261" smd rect
			(at 2.050034 40.375078 270)
			(size 0.519938 1.4986)
			(layers "F.Cu" "F.Mask" "F.Paste")
			(net "M_A_CPU1_SB_DQS_DP<6>")
		)
		(pad "262" smd rect
			(at 2.050034 41.224962 270)
			(size 0.519938 1.4986)
			(layers "F.Cu" "F.Mask" "F.Paste")
			(net "GND")
		)
		(pad "263" smd rect
			(at 2.050034 42.0751 270)
			(size 0.519938 1.4986)
			(layers "F.Cu" "F.Mask" "F.Paste")
			(net "M_A_CPU1_SB_DQ<14>")
		)
		(pad "264" smd rect
			(at 2.050034 42.924984 270)
			(size 0.519938 1.4986)
			(layers "F.Cu" "F.Mask" "F.Paste")
			(net "GND")
		)
		(pad "265" smd rect
			(at 2.050034 43.775122 270)
			(size 0.519938 1.4986)
			(layers "F.Cu" "F.Mask" "F.Paste")
			(net "M_A_CPU1_SB_DQ<15>")
		)
		(pad "266" smd rect
			(at 2.050034 44.625006 270)
			(size 0.519938 1.4986)
			(layers "F.Cu" "F.Mask" "F.Paste")
			(net "GND")
		)
		(pad "267" smd rect
			(at 2.050034 45.47489 270)
			(size 0.519938 1.4986)
			(layers "F.Cu" "F.Mask" "F.Paste")
			(net "M_A_CPU1_SB_DQ<18>")
		)
		(pad "268" smd rect
			(at 2.050034 46.325028 270)
			(size 0.519938 1.4986)
			(layers "F.Cu" "F.Mask" "F.Paste")
			(net "GND")
		)
		(pad "269" smd rect
			(at 2.050034 47.174912 270)
			(size 0.519938 1.4986)
			(layers "F.Cu" "F.Mask" "F.Paste")
			(net "M_A_CPU1_SB_DQ<19>")
		)
		(pad "270" smd rect
			(at 2.050034 48.02505 270)
			(size 0.519938 1.4986)
			(layers "F.Cu" "F.Mask" "F.Paste")
			(net "GND")
		)
		(pad "271" smd rect
			(at 2.050034 48.874934 270)
			(size 0.519938 1.4986)
			(layers "F.Cu" "F.Mask" "F.Paste")
			(net "M_A_CPU1_SB_DQS_DN<7>")
		)
		(pad "272" smd rect
			(at 2.050034 49.725072 270)
			(size 0.519938 1.4986)
			(layers "F.Cu" "F.Mask" "F.Paste")
			(net "M_A_CPU1_SB_DQS_DP<7>")
		)
		(pad "273" smd rect
			(at 2.050034 50.574956 270)
			(size 0.519938 1.4986)
			(layers "F.Cu" "F.Mask" "F.Paste")
			(net "GND")
		)
		(pad "274" smd rect
			(at 2.050034 51.425094 270)
			(size 0.519938 1.4986)
			(layers "F.Cu" "F.Mask" "F.Paste")
			(net "M_A_CPU1_SB_DQ<22>")
		)
		(pad "275" smd rect
			(at 2.050034 52.274978 270)
			(size 0.519938 1.4986)
			(layers "F.Cu" "F.Mask" "F.Paste")
			(net "GND")
		)
		(pad "276" smd rect
			(at 2.050034 53.125116 270)
			(size 0.519938 1.4986)
			(layers "F.Cu" "F.Mask" "F.Paste")
			(net "M_A_CPU1_SB_DQ<23>")
		)
		(pad "277" smd rect
			(at 2.050034 53.975 270)
			(size 0.519938 1.4986)
			(layers "F.Cu" "F.Mask" "F.Paste")
			(net "GND")
		)
		(pad "278" smd rect
			(at 2.050034 54.824884 270)
			(size 0.519938 1.4986)
			(layers "F.Cu" "F.Mask" "F.Paste")
			(net "M_A_CPU1_SB_DQ<26>")
		)
		(pad "279" smd rect
			(at 2.050034 55.675022 270)
			(size 0.519938 1.4986)
			(layers "F.Cu" "F.Mask" "F.Paste")
			(net "GND")
		)
		(pad "280" smd rect
			(at 2.050034 56.524906 270)
			(size 0.519938 1.4986)
			(layers "F.Cu" "F.Mask" "F.Paste")
			(net "M_A_CPU1_SB_DQ<27>")
		)
		(pad "281" smd rect
			(at 2.050034 57.375044 270)
			(size 0.519938 1.4986)
			(layers "F.Cu" "F.Mask" "F.Paste")
			(net "GND")
		)
		(pad "282" smd rect
			(at 2.050034 58.224928 270)
			(size 0.519938 1.4986)
			(layers "F.Cu" "F.Mask" "F.Paste")
			(net "M_A_CPU1_SB_DQS_DN<8>")
		)
		(pad "283" smd rect
			(at 2.050034 59.075066 270)
			(size 0.519938 1.4986)
			(layers "F.Cu" "F.Mask" "F.Paste")
			(net "M_A_CPU1_SB_DQS_DP<8>")
		)
		(pad "284" smd rect
			(at 2.050034 59.92495 270)
			(size 0.519938 1.4986)
			(layers "F.Cu" "F.Mask" "F.Paste")
			(net "GND")
		)
		(pad "285" smd rect
			(at 2.050034 60.775088 270)
			(size 0.519938 1.4986)
			(layers "F.Cu" "F.Mask" "F.Paste")
			(net "M_A_CPU1_SB_DQ<30>")
		)
		(pad "286" smd rect
			(at 2.050034 61.624972 270)
			(size 0.519938 1.4986)
			(layers "F.Cu" "F.Mask" "F.Paste")
			(net "GND")
		)
		(pad "287" smd rect
			(at 2.050034 62.47511 270)
			(size 0.519938 1.4986)
			(layers "F.Cu" "F.Mask" "F.Paste")
			(net "M_A_CPU1_SB_DQ<31>")
		)
		(pad "288" smd rect
			(at 2.050034 63.324994 270)
			(size 0.519938 1.4986)
			(layers "F.Cu" "F.Mask" "F.Paste")
			(net "GND")
		)
		(pad "G1" thru_hole oval
			(at 0 -68.97497)
			(size 2.8194 1.5748)
			(drill oval 2.4384 1.1938)
			(layers "*.Cu" "*.Mask")
			(remove_unused_layers no)
			(net "GND")
			(clearance 0.127)
			(thermal_gap 0.127)
		)
		(pad "G2" thru_hole oval
			(at 0 3.875024)
			(size 2.8194 1.5748)
			(drill oval 2.4384 1.1938)
			(layers "*.Cu" "*.Mask")
			(remove_unused_layers no)
			(net "GND")
			(clearance 0.127)
			(thermal_gap 0.127)
		)
		(pad "G3" thru_hole oval
			(at 0 68.97497)
			(size 2.8194 1.5748)
			(drill oval 2.4384 1.1938)
			(layers "*.Cu" "*.Mask")
			(remove_unused_layers no)
			(net "GND")
			(clearance 0.127)
			(thermal_gap 0.127)
		)
	)
)
